M48
INCH,TZ
T01C.01
T02C.012
T03C.016
T04C.029
T05C.031
T06C.032
T07C.035
T08C.036
T09C.038
T10C.04
T11C.042
T12C.045
T13C.05
T14C.062
T15C.091
T16C.099
T17C.032
T18C.034
T19C.038
T20C.04
T21C.048
T22C.061
T23C.062
T24C.086
T25C.093
T26C.126
T27C.128
T28C.138
;LEADER: 12 
;HEADER: 
;CODE  : ASCII 
;FILE  : 13948-1b-1-8.drl for board 13948-1b.brd ... layers TOP and BOTTOM
;T01 Holesize 1. = 10.000000 Tolerance = +0.000000/-0.000000 PLATED MILS Quantity = 1574
;T02 Holesize 2. = 12.000000 Tolerance = +0.000000/-0.000000 PLATED MILS Quantity = 2140
;T03 Holesize 3. = 16.000000 Tolerance = +0.000000/-0.000000 PLATED MILS Quantity = 762
;T04 Holesize 4. = 29.000000 Tolerance = +0.000000/-0.000000 PLATED MILS Quantity = 164
;T05 Holesize 5. = 31.000000 Tolerance = +0.000000/-0.000000 PLATED MILS Quantity = 3
;T06 Holesize 6. = 32.000000 Tolerance = +0.000000/-0.000000 PLATED MILS Quantity = 6
;T07 Holesize 7. = 35.000000 Tolerance = +0.000000/-0.000000 PLATED MILS Quantity = 17
;T08 Holesize 8. = 36.000000 Tolerance = +0.000000/-0.000000 PLATED MILS Quantity = 12
;T09 Holesize 9. = 38.000000 Tolerance = +0.000000/-0.000000 PLATED MILS Quantity = 4
;T10 Holesize 10. = 40.000000 Tolerance = +0.000000/-0.000000 PLATED MILS Quantity = 18
;T11 Holesize 11. = 42.000000 Tolerance = +0.000000/-0.000000 PLATED MILS Quantity = 3
;T12 Holesize 12. = 45.000000 Tolerance = +0.000000/-0.000000 PLATED MILS Quantity = 20
;T13 Holesize 13. = 50.000000 Tolerance = +0.000000/-0.000000 PLATED MILS Quantity = 5
;T14 Holesize 14. = 62.000000 Tolerance = +0.000000/-0.000000 PLATED MILS Quantity = 2
;T15 Holesize 15. = 91.000000 Tolerance = +0.000000/-0.000000 PLATED MILS Quantity = 2
;T16 Holesize 16. = 99.000000 Tolerance = +0.000000/-0.000000 PLATED MILS Quantity = 4
;T17 Holesize 17. = 32.000000 Tolerance = +0.000000/-0.000000 NON_PLATED MILS Quantity = 2
;T18 Holesize 18. = 34.000000 Tolerance = +0.000000/-0.000000 NON_PLATED MILS Quantity = 1
;T19 Holesize 19. = 38.000000 Tolerance = +0.000000/-0.000000 NON_PLATED MILS Quantity = 2
;T20 Holesize 20. = 40.000000 Tolerance = +0.000000/-0.000000 NON_PLATED MILS Quantity = 2
;T21 Holesize 21. = 48.000000 Tolerance = +0.000000/-0.000000 NON_PLATED MILS Quantity = 1
;T22 Holesize 22. = 61.000000 Tolerance = +0.000000/-0.000000 NON_PLATED MILS Quantity = 2
;T23 Holesize 23. = 62.000000 Tolerance = +0.000000/-0.000000 NON_PLATED MILS Quantity = 4
;T24 Holesize 24. = 86.000000 Tolerance = +0.000000/-0.000000 NON_PLATED MILS Quantity = 8
;T25 Holesize 25. = 93.000000 Tolerance = +0.000000/-0.000000 NON_PLATED MILS Quantity = 2
;T26 Holesize 26. = 126.000000 Tolerance = +0.000000/-0.000000 NON_PLATED MILS Quantity = 10
;T27 Holesize 27. = 128.000000 Tolerance = +0.000000/-0.000000 NON_PLATED MILS Quantity = 2
;T28 Holesize 28. = 138.000000 Tolerance = +0.000000/-0.000000 NON_PLATED MILS Quantity = 4
%
G90
T01
X440000Y5000
X460000
X485000
X515000
X545000
X575000
X685000
X695000Y20000
X715000Y5000
X725000Y20000
X745000Y5000
X755000Y20000
X775000Y5000
X785000Y20000
X805000Y5000
X815000Y20000
X835000Y5000
X850000Y20000
X865000Y5000
X880000Y20000
X895000Y5000
X910000Y20000
X925000Y5000
X940000Y20000
X955000Y5000
X970000Y20000
X985000Y5000
X1000000Y20000
X1015000Y5000
X1045000
X1060000Y20000
X1075000Y5000
X1090000Y20000
X1105000Y5000
Y15000
X1211500Y35500
Y5500
X1235500Y5000
X1268000
X1307500
X1337500
X1394122Y5878
X1211500Y65500
X1105000Y75000
X937000Y63000
X935000Y51500
X902000Y63000
X874000Y56000
X873500Y61500
X862500Y65000
X700000Y60500
X294500Y98500
X299300Y84200
X330250Y80000
X428375Y119735
X471480Y105660
X521700Y114000
X866112Y85626
X1105000Y105000
X1211500Y107500
Y85500
Y137500
X1105000Y135000
X947500Y153000
X945000Y141500
X568500Y147500
X546500
X538875Y138000
X466500Y144500
X466464Y151000
X463969Y147610
X461685Y150386
X460300Y141100
X459069Y151980
X457929Y132500
X456429Y135000
X455731Y154302
X454929Y146500
X454676Y137495
X453929Y140334
X453599Y156693
X451679Y148250
X450209Y129230
X448669Y126510
X447389Y129580
X443928Y148811
X443890Y142565
X443936Y155118
X443909Y145650
X443871Y158278
X443891Y151999
X442323Y126000
X440931Y129061
X440765Y145670
X439540Y124500
X437945Y127159
X437598Y155118
Y148818
X437599Y136221
Y142520
X435640Y123000
X434449Y155118
X434450Y142520
Y136221
X432540Y123000
X431407Y136285
X431300Y142520
X431348Y125911
X428151Y142520
X428149Y148818
X428116Y136218
X425001Y142520
X424999Y148818
X425000Y136220
X423686Y126215
X421851Y142520
Y136221
X421850Y148818
X421590Y128500
X418940Y125000
X418702Y136221
Y142520
X418700Y148818
X415552Y142520
Y136221
X415551Y148818
X415549Y151990
X413540Y128500
X412401Y158267
X412429Y136210
X412415Y148794
X412402Y155118
X412403Y142520
X412401Y151967
X406103Y139371
X406125Y148804
X406103Y142520
X406102Y158267
X406110Y145660
X406102Y155117
X402954Y145670
X402953Y139370
X402950Y133050
X402954Y142520
X402938Y151950
X402800Y129180
X399835Y139375
X399779Y142531
X399819Y151950
X399783Y136237
X399804Y145670
X396653Y155117
X396683Y139362
X396655Y142520
Y145670
X396653Y158266
X396639Y151990
X393510Y139340
X393505Y145670
Y142520
X393519Y151990
X392240Y129000
X390355Y142520
Y139371
Y145670
X390354Y136221
X390339Y151990
X387206Y145670
X387173Y139376
X387206Y142520
X387219Y158290
X384056Y145670
X384055Y155117
X384093Y151968
X384056Y142520
X384055Y158266
X384019Y139371
X383680Y129030
X380920Y139370
X380907Y142520
X380906Y136220
X380888Y148799
X377787Y148812
X377757Y142520
X377750Y139400
X377757Y145670
X377759Y152000
X377765Y155146
X374570Y158267
X374600Y139390
X374606Y136221
X374589Y155110
X374607Y142520
X371458
X371493Y145667
X371482Y133058
X371456Y136221
X371455Y148854
X371457Y155080
X368271Y158268
X368333Y155107
X368307Y133071
X368305Y139401
X368296Y136246
X368314Y142505
Y145680
X368329Y151956
X368333Y148827
X365182Y142532
X365146Y151942
X365133Y129133
X365140Y155100
X362009Y155119
Y148819
Y142520
X357394Y131496
X353740Y133300
X352040Y143000
X349829Y153400
X347000Y120040
X340000
X338000Y127500
X337400Y134500
X334000Y147600
X331040Y152601
X330929Y148600
X330900Y134500
X330400Y141600
X328700Y154400
X328629Y146800
X319014Y152977
X318200Y159100
X317248Y156000
X313402
X312500Y159100
X311500Y153000
X307129Y143000
X305029Y147700
X299000Y148000
X304100Y167000
X304300Y160200
X311300Y167000
X351320Y194520
X351731Y190274
X351929Y162200
X353085Y187485
X354540Y199000
X355040Y180000
X355090Y195660
X355084Y172441
X355139Y190099
X358850Y196050
X358848Y174010
X358879Y192929
X358858Y177128
X362036Y177155
X362034Y161406
X362036Y170876
X362017Y183492
X361987Y189747
X365176Y161400
X365187Y186605
X365158Y164554
X365186Y177175
Y170876
X368325Y164585
X368326Y161400
X368334Y167706
X368309Y170830
X368336Y189755
Y192904
X368320Y183460
X368308Y177202
X368307Y196062
Y199211
X371489Y161411
X371457Y173978
X371485Y177175
X371470Y167741
X374582Y161404
X374606Y189763
X374577Y164559
X374560Y177210
X374606Y192912
X377732Y167703
X377741Y177188
X377731Y180302
X377718Y161417
X377750Y170846
X377755Y189763
Y199211
Y192912
Y196062
X380928Y167701
X380944Y161417
X384030Y177120
X384032Y174003
Y167703
X384041Y170888
X384036Y189747
X384055Y196062
Y186613
Y192912
X387209Y192930
X387205Y167715
X387204Y177164
X390354Y167715
X390392Y186614
X393541Y180315
X393519Y192900
X393542Y186614
X393490Y174039
X393528Y167702
X396653Y180314
Y192912
Y199211
Y167715
Y174015
X396654Y186614
X399790Y174039
X399840Y180315
X399827Y167702
X399791Y192938
X399841Y186614
X402952Y192912
Y180314
Y186613
X402977Y174003
X402952Y167715
X406101Y186613
X406126Y174003
X406128Y192901
X406127Y161404
X406140Y167716
X406139Y180315
X409251Y192912
Y167715
Y174015
Y186613
X409288Y180315
X412400Y180314
X412439Y186614
X412426Y167703
X412427Y161404
X412426Y174003
X412428Y192901
X415551Y186614
X415587Y180315
X415575Y167703
X415551Y174015
Y192912
X418726Y180303
Y174003
Y167703
X418727Y192902
X418701Y186614
X421876Y192902
Y186603
Y180304
Y174005
Y167705
X424999Y161416
Y199211
Y192912
X428149Y183463
Y192912
Y199211
Y177164
Y170865
Y161416
Y164565
X431299Y186613
Y177164
Y161416
Y183463
Y170865
Y164565
X434449Y199212
Y174015
Y192913
Y167716
Y180314
X434448Y186613
X434449Y161417
X437598Y180314
Y161417
Y192913
Y167716
Y199212
Y186614
Y174015
X440769Y183480
X443897Y196063
X443910Y174041
X443899Y161430
X443879Y180320
X443898Y199212
X443919Y183480
X443882Y167737
X443899Y164530
X443897Y192914
X443887Y177138
X447047Y189764
X447063Y199234
X450196Y189764
X451329Y165570
X451292Y197637
X452329Y194300
X454329Y199800
X455929Y192800
X456229Y196700
X458429Y185000
X465679Y192600
X469429Y179500
Y165590
Y172500
X473131Y169131
X477429Y162500
X480500Y181800
X710100Y182700
X756000Y180000
X959900Y180700
X974500Y188500
X975007Y194300
X1084500Y223500
X1055000Y214500
X691400Y231100
X605000Y209500
X604500Y205000
Y227500
Y200500
Y223000
X603500Y214000
Y218500
X594500Y236000
X579221Y237250
X533441Y211775
X464570Y215750
X458029Y213469
X457798Y217769
X457729Y206800
X456929Y224507
X456479Y202400
X455429Y227500
X453829Y215600
X453729Y219300
X452929Y203900
X452393Y210236
X451929Y229800
X448840Y225775
X445892Y225995
X443897Y202363
Y211811
Y208662
Y205512
X443113Y226339
X441379Y229700
X439980Y232126
X437598Y211810
Y218109
Y205511
X437112Y232239
X436529Y229500
X434414Y205514
X434448Y218109
X434449Y211810
X434334Y226789
X432307Y224857
X431336Y218111
X429444Y230192
X428150Y211810
X428172Y221320
X428149Y202361
X428047Y218049
X426147Y230982
X424979Y218127
X425001Y211810
X424999Y202361
X422630Y227232
X421850Y218109
Y211810
X420714Y225190
X420500Y234500
X419000Y227405
X418701Y211810
X418729Y221268
Y218100
X415551Y218109
Y211810
X412767Y233162
X412402Y211810
X412401Y205510
X409249Y214965
X406099Y214950
X406102Y211810
X402953
X400000Y237500
X399803Y211810
Y208660
Y221259
Y218109
X396653Y208660
Y205511
X396654Y211810
Y202362
X395500Y237000
X393503Y205510
Y208660
Y211809
X393504Y218109
X390354Y221259
Y218109
Y224408
X384055Y202361
Y211810
X380906
X377756
X377755Y202361
X374607Y218110
X374606Y211810
X371457
X368307Y205511
Y202361
X365158Y211810
X409500Y271500
X436500Y241000
X438500Y250000
X542000Y249000
X559750Y264500
X563250Y262500
X580828Y260028
X780000Y250000
X1045000Y266600
X1102000Y250000
X1102500Y264500
X539300Y317600
X534000Y317500
X528600Y316700
X522365Y316365
X522345Y311699
X513500Y315800
X513407Y311502
X506000Y317500
X505678Y310921
X498955Y316900
X498855Y311100
X493855Y312700
X490455Y319200
X488155Y315700
X483955Y318600
X431023Y317283
X427965Y318293
X424555Y318000
X419913Y318051
X417650Y316400
X416482Y319022
X392589Y317729
X389500Y319150
X362500Y286000
X348000Y292500
X326000
X307500Y299000
X384160Y328812
X386755Y326100
X390230Y349327
X391325Y324520
X391628Y358852
X391555Y338350
X393061Y346800
X393755Y350500
X394055Y335000
X394915Y359725
X396055Y338000
X397555Y345146
X397983Y333998
X398055Y350296
X398555Y339283
X400055Y343146
X400523Y325283
X400885Y354120
X400983Y334054
X404920
Y330117
X404935Y353840
X404965Y342120
X408857Y345865
Y357676
Y341928
Y353739
Y334054
Y330117
X412794Y357676
X412815Y349860
X412794Y353739
Y337991
Y330117
Y341928
Y334054
X416615Y349930
X416555Y357500
X416731Y330117
Y353739
Y334054
Y337991
Y341928
X416950Y321783
X420668Y330117
Y337991
Y341928
Y357676
Y349802
Y345865
Y334054
Y353739
X424023Y320783
X424605Y330117
Y345865
Y349802
Y357676
Y337991
Y341928
Y334054
Y353739
X428542Y357676
Y334054
Y341928
Y349802
Y345865
Y353739
Y337991
Y330117
X430513Y320841
X432365Y341880
X432523Y330283
X432585Y345850
X432605Y337880
X434448Y320783
X436416Y330117
Y353739
Y334054
Y345865
X440353Y349802
Y341928
Y345865
Y330117
Y357676
Y334054
Y353739
X440555Y338000
X441335Y321000
X444290Y341928
Y345865
Y357676
Y337991
Y330117
Y353739
Y349802
X444555Y334000
X448000Y346000
X448227Y353739
Y349802
Y341928
Y334054
Y357676
Y330117
X452055Y338000
X452223Y333983
X452165Y349470
X455825Y349840
X456103Y330117
Y357676
Y341928
X456055Y338000
X456103Y353739
Y334054
X460040Y357676
Y349802
Y330117
Y334054
Y341928
Y337991
X463977Y357676
Y330117
Y341928
Y334054
Y337991
X467300Y320100
X467914Y337991
Y345865
Y357676
Y334054
Y353739
Y330117
Y349802
X471851Y322243
Y337991
Y357676
Y353739
Y326180
Y349802
X475788Y341928
Y330117
Y357676
Y349802
X479725Y357676
Y330117
X479655Y322500
X479725Y349802
Y341928
Y337991
X481255Y320000
X483662Y341928
Y330117
Y337991
Y334054
Y326180
Y345865
Y357676
Y353739
Y349802
X484000Y322000
X487155Y321900
X487500Y333833
X487599Y357676
Y353739
Y337991
Y330117
Y349802
Y341928
Y326180
Y345865
X491536Y334054
X491500Y353500
X491536Y341928
X495473Y334054
Y341928
X499410Y322243
X505523Y332086
X507955Y356100
X511455Y338700
X511500Y348000
X521800Y322000
X523500Y347500
Y357500
Y342000
Y352000
X526800Y359600
X527667Y322182
X529400Y352800
X530000Y342000
X530100Y347200
X539200Y324100
X884500Y323500
X1132500Y333000
X1144425Y325500
X1055500Y360000
X547500Y360168
X523100Y364300
X519500Y365500
X505523Y371456
Y363582
X503347Y397048
Y381300
Y389174
X495473Y385237
Y393111
Y377363
X491536Y369487
Y385237
Y361613
Y381300
Y377363
Y397048
Y389174
Y393111
X487643Y361523
X487603Y369483
X483662Y361613
X483663Y365463
X483683Y369403
X479725Y397048
Y385237
Y361613
Y369487
Y365550
Y389174
Y381300
Y377363
Y393111
X475788Y377363
Y389174
Y397048
Y361613
Y393111
Y369487
Y381300
X471851Y377363
Y389174
Y381300
Y393111
Y361613
Y397048
Y369487
X467914Y397048
Y393111
Y377363
Y369487
Y385237
Y361613
Y365550
Y381300
Y389174
X463977Y361613
Y393111
Y369487
Y365550
Y377363
Y381300
Y385237
Y389174
Y397048
X460040Y361613
Y397048
Y365550
Y385237
Y381300
Y377363
Y393111
Y369487
Y389174
X456103Y365550
Y385237
Y361613
Y389174
Y381300
Y369487
Y377363
Y393111
Y397048
X448227Y381300
Y377363
Y393111
Y369487
Y389174
Y385237
Y361613
Y365550
Y397048
X444290Y377363
Y397048
Y365550
Y381300
Y389174
Y385237
Y369487
X440353Y377363
Y389174
Y369487
Y397048
Y365550
Y381300
X436416Y377363
Y381300
Y389174
Y397048
Y361613
Y369487
X432479Y397048
Y381300
Y389174
Y393111
Y385237
Y377363
Y369487
Y361613
X428555Y393000
X428542Y369487
Y385237
Y389174
X428500Y377000
X428542Y365550
Y381300
Y361613
Y397048
X428445Y373550
X424605Y381300
Y365550
Y389174
Y393111
Y397048
Y361613
Y369487
Y385237
X420668Y369487
Y385237
Y377363
Y389174
Y365550
Y381300
Y393111
Y397048
Y361613
X416731Y369487
Y385237
Y393111
Y377363
Y365550
Y361613
Y397048
Y389174
Y381300
X412794Y397048
Y365550
Y389174
Y361613
Y369487
Y381300
Y385237
Y393111
Y377363
X408857Y365550
Y389174
Y385237
Y377363
X408925Y361680
X408857Y393111
Y397048
Y369487
X404920Y393111
Y389174
Y397048
Y369487
X400983Y397048
X400395Y362450
X399923Y372000
X397117Y364138
X396490Y388597
X395855Y366890
X394935Y385150
X392991Y365797
X391215Y384900
X390543Y391950
X387515Y365500
X387265Y384370
X382803Y385207
X371781Y387924
X368555Y385000
Y376500
Y389000
X368165Y393402
X368055Y380500
X367665Y363430
X387000Y404275
X388500Y400575
X399555Y438500
X400983Y404922
Y400985
Y416733
X404555Y430500
X404920Y416733
Y420670
Y400985
Y404922
X406555Y428300
X408857Y400985
Y424607
Y416733
Y420670
Y412796
Y408859
Y404922
X412794Y420670
Y408859
Y412796
Y416733
Y424607
Y404922
Y400985
X416731
Y420670
Y412796
Y416733
Y424607
Y404922
X420668Y408859
Y404922
Y400985
X423555Y431500
X424605Y404922
Y412796
Y408859
Y400985
X428542
X428523Y416683
X428542Y404922
Y408859
X432479Y412796
Y404922
Y408859
Y400985
X434723Y426283
X436416Y408859
Y404922
Y400985
X436523Y416683
X440353Y400985
Y408859
Y412796
Y404922
X442535Y426770
X444323Y416883
X444290Y404922
Y408859
Y400985
X448227Y404922
Y412796
Y408859
Y400985
X450725Y425460
X452123Y416783
X452223Y404883
Y408783
X456103Y400985
Y412796
X456223Y404883
Y408783
X460040Y412796
Y400985
X460023Y408883
X463977Y404922
Y400985
Y408859
X467914
Y412796
Y400985
Y404922
X471851Y416733
Y400985
Y412796
X475788Y400985
Y424607
Y412796
X479725Y416733
Y412796
Y400985
X483662Y404922
Y424607
Y412796
Y408859
X487599Y420670
Y404922
Y424607
Y416733
X491536Y424607
Y400985
Y404922
Y412796
Y416733
Y420670
Y408859
X495473
Y416733
Y400985
Y412796
Y424607
Y420670
X499410Y424607
Y408859
Y416733
Y420670
Y412796
X503347Y404922
Y408859
Y420670
X1089500Y405000
X1088000Y461000
X1015000Y477500
X720500Y478750
X124500Y515500
X166200Y506500
X172000Y486400
X305155Y504900
X306155Y497700
X320238Y497183
X320338Y507683
X356055Y502000
X356555Y513000
X357055Y507000
X361155Y496203
X370500Y518000
X865000Y488500
X1022000Y492500
X1103300Y492000
X1355900Y536600
X1354900Y522600
X1352400Y533600
X1351900Y524600
X1322900
X1322400Y533100
X1319400Y522100
X1318700Y533500
X1249773Y551500
X632500Y530000
X344055Y529000
X342971Y525750
X340055Y524000
X316273Y520282
X128000Y544050
X121200Y584278
X182000Y577500
X234000Y562000
X236500Y574000
X242500Y565500
X1305000Y596500
X1378800Y594900
X1379600Y584200
X1380925Y598315
X1381415Y581195
X1384400Y598300
X1385135Y581195
X1387200Y584100
X1384400Y601900
X1381578Y607117
X1381637Y611225
X1380925Y602035
X1378082Y614266
X1377996Y610847
Y607382
X1377800Y603800
X1306443Y618985
X1306423Y608164
X1305435Y603918
X1305217Y612412
X1201250Y627000
X1143000Y629000
X1126500Y614500
X1113500Y614250
X1113000Y630500
X1105000
X1062940Y629945
X1022500Y637500
X1258562Y672438
X1190500Y674207
X1185965Y676573
X1182831Y679666
X1182815Y676573
X1182803Y670234
X1179667Y679655
X1179662Y673421
X1179653Y670234
X1176526Y667092
X1176534Y673368
X1176525Y679676
X1176534Y676555
X1176503Y670218
X1176506Y663916
X1173403Y670237
X1173332Y663938
X1173349Y667099
X1173309Y673406
X1170181Y670240
X1170192Y667100
X1167692Y674996
X1167098Y663932
X1167034Y667092
X1163917Y670275
X1163914Y673352
X1163944Y667076
X1163946Y663946
X1160770Y673421
X1160768Y676535
X1160741Y667099
X1160748Y657657
Y660807
X1160741Y663949
X1159100Y640800
X1157655Y667087
X1157599Y663956
X1157613Y673418
X1154470Y673363
X1154496Y667096
X1154487Y670256
X1152090Y677010
X1151354Y663936
X1151337Y670256
X1151282Y667088
X1151337Y660807
X1148188Y667106
Y670256
X1148150Y663956
X1145020Y670200
X1144983Y667085
X1141954Y676581
X1141868Y670273
X1141900Y663944
X1141600Y673590
X1139245Y675106
X1138757Y663937
X1138708Y667113
X1136150Y676500
X1135685Y679613
X1135598Y667080
X1135589Y673368
X1135595Y670225
X1135553Y663957
X1132398Y667102
X1132423Y663902
X1132402Y673405
X1132395Y670225
X1132440Y676555
X1132421Y679648
X1129290Y676555
X1129271Y670275
X1129272Y673350
X1126102Y676518
X1126121Y679722
X1122985Y670262
X1122938Y676540
X1114500Y645000
X1088400Y647484
X1074500Y665500
X1074000Y660500
X1065978Y664568
X1062700Y672600
X1011500Y667500
X1002500Y653000
X182500Y677500
X50000Y659500
X58804Y699720
X176938Y680465
X238500Y705000
X253500Y707250
X622500Y696500
X625000Y706000
X1041410Y699834
Y690694
Y695394
X1054080Y680630
X1063056Y681554
X1118630Y714820
X1119265Y683864
X1126093Y704874
X1126116Y692279
X1126114Y701703
X1126121Y714368
X1126117Y685952
X1126122Y689171
X1126121Y711218
X1126157Y695435
X1126155Y708029
X1129238Y704878
X1129285Y708056
X1129277Y711210
X1129290Y692303
X1129273Y689170
X1129260Y714350
X1129270Y701714
X1129278Y682804
X1129289Y686005
X1129290Y698564
X1132417Y711189
X1132423Y695469
X1132445Y714345
X1132406Y704904
X1132440Y701714
X1132434Y682860
X1132440Y692265
Y698564
Y686004
X1132459Y717481
X1135589Y695415
Y701714
X1135551Y685967
X1135570Y711218
X1135589Y682854
X1136304Y707482
X1138320Y710066
X1138400Y705300
X1138729Y714360
X1138730Y717480
X1139000Y685667
X1139858Y692074
X1140710Y707750
X1141840Y714339
X1141765Y711030
X1141870Y717518
X1141868Y680064
X1144880Y707720
X1145000Y711200
X1145053Y714327
X1148150Y695452
Y692303
Y682854
Y689153
Y698602
Y686004
X1148169Y711219
X1148167Y717517
X1151300Y689153
Y695452
Y682854
X1151318Y717518
X1151300Y686004
X1151307Y714306
X1151300Y698602
Y692303
X1151352Y711178
X1154218Y679964
X1154449Y682854
Y698602
Y692303
Y695452
Y686004
Y689153
X1154430Y717481
X1154434Y714335
X1157637Y717463
X1157599Y689153
X1157581Y714331
X1157636Y711200
X1157599Y695452
Y686004
Y692303
Y698602
X1157670Y707960
X1160748Y695452
Y689153
Y686004
Y682854
Y692303
Y698602
X1163898Y695452
Y717462
Y686004
Y698602
X1163905Y711206
X1163898Y689153
Y692303
X1163968Y708000
X1167048Y714312
X1167049Y717501
X1167103Y711107
X1169800Y682200
X1170248Y714330
X1170199Y717501
X1171200Y706170
X1173015Y708329
X1173347Y714350
X1173262Y711119
X1173365Y695397
X1173392Y685974
X1173384Y692265
X1173350Y698590
X1173389Y689121
X1173400Y717480
X1176489Y717469
X1176482Y682840
X1176515Y704845
Y708045
X1176496Y698564
X1176503Y714342
X1176515Y711144
X1176520Y685970
X1176529Y692276
X1176496Y695415
X1179671Y698565
X1179660Y704850
X1179664Y695466
X1179676Y711207
X1179660Y708050
X1179663Y685959
X1179703Y714331
X1179685Y692292
X1179678Y689111
X1182785Y685977
X1182802Y714356
X1182815Y701696
X1182796Y708013
Y695415
X1182817Y689155
X1182813Y698619
X1185945Y695415
X1190000Y705500
Y699500
X1196000Y710500
X1203500Y698520
X1218040Y719850
X1257500Y710500
X1259000Y699500
X1272500Y712500
X1272700Y694900
X1276000Y694000
X1277000Y712500
X1279600Y694800
X1287962Y710490
X1289500Y716500
X1307150Y691500
X1318000Y696500
X1319000Y708000
X1310500Y737500
X1307000Y732500
Y729100
X1300491Y732991
X1292500Y730478
X1275000Y732000
X1259500Y724000
X1249000Y723250
X1199500Y743500
X1176499Y720609
X1175000Y734870
X1173348Y720613
X1171500Y733725
X1169282Y729708
X1167048Y720612
X1167000Y727500
X1166100Y731500
X1164200Y744500
X1163898Y720612
X1163830Y747899
X1157643Y720642
X1157112Y731702
X1157000Y734500
X1152400Y727600
X1152248Y730404
X1152023Y733299
X1150734Y736950
X1149470Y734451
X1148135Y720634
X1141904Y720633
X1138685
X1137030Y745300
X1132398Y720624
X1128959Y729952
X1127183Y740805
X1126969Y727981
X1126955Y731909
X1126885Y736721
X1126671Y744629
X1124978Y747578
X1124497Y734140
X1124326Y738960
X1123393Y743726
X1110790Y738850
X1061356Y753354
X881000Y736500
X1001100Y776500
X1061696Y761294
X1116550Y783600
X1119060Y791083
X1120400Y781600
X1120529Y786350
X1121215Y769936
X1121646Y799924
X1123254Y792663
X1124360Y788390
X1124460Y768140
X1125900Y764200
X1126360Y792640
X1127160Y788837
X1127945Y769970
Y799935
X1129501Y776929
X1129497Y792673
X1130610Y788820
X1130900Y766700
X1132600Y784822
X1132684Y792636
X1134145Y788450
X1134245Y769145
X1136236Y782142
X1138545Y787952
X1138931Y792658
X1138961Y776940
X1138970Y795830
X1140650Y782496
X1141700Y785113
X1142120Y795830
X1142095Y773774
X1142110Y792660
X1142086Y789513
X1142323Y780250
X1143470Y782805
X1145265Y776945
X1145270Y795830
Y792670
X1145740Y789140
X1146200Y766300
X1146370Y769310
X1150310Y783840
X1151592Y773748
X1151564Y776924
X1151565Y787951
X1151590Y792660
X1153219Y781303
X1154200Y788900
X1154700Y795790
X1154712Y792690
X1154800Y799000
X1157866Y795844
X1157871Y773728
X1158100Y769700
X1158092Y787715
X1161022Y785693
X1161051Y792660
X1161545Y788844
X1162450Y769190
X1162693Y780865
X1163605Y783513
X1164196Y795814
X1165063Y787500
X1165492Y780957
X1167002Y767508
X1167320Y770290
X1167277Y792658
X1167326Y776936
X1167330Y795830
X1167410Y785530
X1170718Y782118
X1170911Y784912
X1170950Y795960
X1171108Y777368
X1170300Y809610
X1165300
X1160300
X1157990Y827000
X1155390Y818000
X1154300Y809610
X1149400Y800000
X1142010Y809500
X1141100Y831600
X1135500Y835000
X1135000Y810000
X1134244Y799984
X1131095Y799965
X1124796Y800150
X1123500Y832470
X1121000Y808500
X599000Y804000
X1027504Y853366
X339000Y878500
X336000Y871500
X109000Y844220
X339000Y894000
Y885500
X396500Y910500
X419500Y914000
X388750Y951750
X337300Y949500
X111000Y981500
X112900Y988500
X379500Y963500
X387061Y986061
X389500Y992000
X723000Y996500
X727558
X731498
X739368Y996610
X810000Y980000
X840000
X870000
X900000
X1010000
X1040000
X1070000
X1100000
X1130000
X1155000
X1185000
X1215000
X1245000
X1275000
X1300000
X1330000
X1360000
T02
X40945Y384710
X47483Y387776
X43883Y387769
X48820Y412435
X39370Y412673
X40054Y823970
X35304Y832220
X44804Y837220
X36004Y839500
X8442Y847311
X44500Y851500
X8000Y853500
X8200Y857700
X49000Y861500
X37232Y877242
X37211Y881115
X37758Y884674
X40304Y887220
X42554Y891720
X34304Y897720
X38804Y906220
X47804Y906720
X43804Y907720
X41304Y927220
X41500Y941500
X46500Y944500
X52804Y943220
X97804Y940720
X52804Y938795
X52770Y932686
X62770
X57770
X55270Y929186
X60270
X50270
X95700Y926300
X64804Y907720
X60804
X56804Y907220
X52304Y906720
X72770Y906488
X81804Y888720
X98304Y888220
X81304Y884470
X51304Y882220
X51896Y878668
X52000Y872720
X76304Y869720
X72304
X52304Y868220
X55304Y849720
X83838Y848133
X87928Y848107
X76804Y847720
X70909Y847325
X79000Y836500
X84221Y836078
X65804Y835720
X69804
X92304
X87804
X57804Y834720
X61804
X77500Y832000
X66022Y827254
X55022Y826720
X73772Y822004
X85804Y816220
X57304Y815720
X61304Y815220
X84804Y808720
X61492Y803004
X57772Y801504
X99804Y799720
X85204Y798220
X82804Y794920
X59272Y790504
X71804Y789720
X86404Y774720
X77804Y773720
X85304Y768720
X93347Y765754
X68762Y764239
X80624Y764241
X85672Y763504
X96060Y762476
X76272Y762504
X64683Y762056
X83112Y760720
X68910Y760642
X75432Y758844
X65272Y758504
X55304Y746220
X62704Y739620
X64272Y736004
X83849Y735513
X75432Y735059
X87772
X80272Y735103
X92365Y735040
X77272Y724004
X68147Y722511
X71846Y722426
X76804Y710220
X81304
X58804
X99804Y709220
X94804Y708220
X63304Y706720
X73804Y699720
X64304Y698720
X97737Y698653
X95304Y686220
X55304Y669720
X89804
X95304Y663720
X60304Y663220
X76804Y662720
X52000Y655500
X77165Y412590
X58270Y412485
X67715Y412518
X71883Y387976
X76083
X66483Y387876
X56883
X62783Y387776
X53183Y387676
X69290Y384865
X78740Y384915
X50395Y384679
X59840
X145500Y283500
X127654Y293453
X132500Y312500
X112654Y314453
X124500Y316000
X132123Y318877
X123654Y320953
X131500Y324000
X122906Y331953
X134874Y354709
X147374
X127301
X131147
X122874
X143147
X139301
X147500Y472100
X135500Y511000
X132500Y547000
Y551500
Y556000
Y559600
X136000Y566000
X140500Y568000
X136500Y569700
X144000Y572500
X136500Y573300
Y576900
Y580500
X133500Y582500
X125050Y583000
X134000Y587000
X126500Y587500
X121685Y587919
X149100Y661100
X111304Y663720
X130000Y666500
X143010Y676400
X111907Y698617
X143500Y710500
X100804Y774720
X141054Y795820
X129304Y798720
X115804
X146304Y804220
X146500Y808220
X113222Y831222
X105000Y834500
X112500Y835000
X122500Y845500
X110500Y848500
X115500
X128000Y870500
X124054Y892220
X114054Y892720
X109054
X119054
X129100Y892924
X132804Y894220
X102304Y895220
X121600Y895266
X126554Y895470
X116554Y895720
X106554
X111554Y896220
X131554Y929470
X111554Y929720
X126554Y929882
X116600Y929924
X121598
X114054Y932470
X119099Y932516
X124098Y932515
X129054Y932720
X109054
X108804Y938795
X101804Y940720
X105804Y943220
X115500Y983500
X118000Y991500
X174500Y901500
X163000Y901000
X168500
X181000
X158000
X188000
X197000
Y897000
X190500Y894000
X195000Y891500
X199000
X187000Y878000
X172000Y868000
X168400
X157500Y867500
X183000Y865750
X185000Y856000
X185500Y848260
X179500Y847000
X186000Y841500
X152500Y840000
X170500Y835500
X174000Y830500
X154500Y812500
X150900
X191875Y803125
X150225Y790412
X198000Y785000
X194500Y724000
X163000Y710500
X153500Y690275
X172040Y688960
X166875Y678285
X162500Y670000
X166000Y662500
X157750Y662250
X166500Y650500
X167469Y588969
X152948Y587000
X156900Y586500
X160500
X189500Y573500
X175055Y569500
X198500Y563000
X180555Y560500
X175993Y559938
X163305Y554750
X195865Y552940
X154625Y550290
X195725Y540750
X154755Y539310
X170339Y537396
X185000Y533562
X177493Y533493
X189355Y526470
X163225Y522080
X185305Y521100
X153050Y486500
X171500Y478699
X182800Y471300
Y465800
X160000Y465500
X190800Y462800
X158500Y461500
X191800Y457300
X187300
X192500Y431500
X162801Y354709
X170374
X151301
X158874
X166647
X155147
X189000Y347600
X192874Y345457
Y341611
Y337907
Y334307
Y330461
X152995Y329119
X167993Y328699
X183374Y328709
X171874
X164147Y328699
X175776Y328749
X179622
X159674Y328609
X155874Y326957
X192874Y326209
X198864Y323297
X155874Y323111
X184295Y322209
X192795Y321709
X180315Y321209
X159774Y320709
X171295
X153437Y320458
X196063Y319209
X186614Y319028
X190295Y318709
X155874Y317807
Y313961
Y310209
X193841Y297755
X181889Y297303
X188295Y297209
X172285Y296964
X162595Y296709
X197245Y296571
X185039Y295209
X191295
X175242Y294909
X179088
X169639Y294309
X165793
X204285Y294909
X213733
X209887
X200439
X217295Y296709
X207086Y297418
X205511Y320709
X214960Y321044
X212134Y323297
X202710
X208338
X232500Y419000
Y425000
Y431000
X212500Y435000
X204500Y470000
X243755Y490890
X229055Y497000
X246613Y501365
X245205Y504679
X242003Y506327
X234755Y509700
X237055Y513500
X216500Y516000
X207773Y516562
X239555Y519500
X228319Y524798
X234185Y527138
X248855Y532300
X208305Y536320
Y548670
Y562640
X203000Y564500
X201000Y625500
X230000Y680500
X212500Y716500
X204500Y721000
X221000Y723000
X212500Y786000
X218000Y801500
X204500Y817500
X232000Y825000
X228000
X223500Y825500
X240000Y829250
X247500Y829500
X205500Y830000
X215250Y833750
X222000Y853500
X227000Y858000
X222000Y858500
X217000
X237953Y861453
X204000Y862000
X222000Y863500
X236500Y866000
X212000Y891500
X208000Y892000
X222000Y893600
X203500Y894000
X205500Y897000
X231500Y898500
X205500Y901000
X278050Y958500
X273678Y958000
X268178Y955500
X280500Y955000
X269000Y921500
X274000
X276500Y888500
X270000Y870000
Y865500
X250362Y865000
X253610Y863447
X261500Y857500
X251500Y855500
X252500Y851500
X252000Y846500
X251000Y835500
X273000Y674000
X253555Y613500
X258500
X253500Y608500
X258500
X261255Y549000
X257555
X252055Y548760
X265455Y544853
X271451Y544616
X272571Y541150
X282555Y540700
X278676Y539500
X283038Y536850
X269555Y536000
X278367Y535140
X263555Y534500
X292555Y533043
X266055Y531725
X275555Y531500
X256055Y531016
X291755Y529000
X260555Y525500
X291530Y525407
X286555Y524524
X253679Y523137
X275055Y521825
X283103Y520208
X286588Y519305
X260605Y519245
X282626Y516639
X260288Y514589
X279997Y514179
X264655Y511100
X250055Y510800
X293273Y509500
X292045Y504897
X259055Y500500
X292525Y498780
X298662Y479783
X299395Y449160
X293929Y342000
X297929Y336000
Y332000
X268300Y219800
X299831Y144328
X296200Y94400
X336700Y4300
X341200
X346000Y4400
X324500Y6000
Y10500
X316900Y65900
X320500Y66000
X339500Y75500
X309500Y78500
X311500Y81500
X337500Y84250
X313250Y85250
X343000Y89000
X319309Y89503
X327000Y89500
X323000
X333000Y90500
X302000Y94300
X317660Y96400
X317500Y101000
X324200Y101900
X346000Y102000
X342000
X314000Y102500
X330000Y118500
X334500
X321500
X325929
Y127700
X329929Y128500
X334600Y129468
X348429Y130000
X334600Y133031
X327100Y136294
Y139857
X319800Y143052
X303677Y144328
X319800Y146898
X326422Y148944
Y152507
X309698Y163800
X305852
X345929Y183000
X340679Y204900
X332429Y210000
X316129Y213000
X322229Y218800
X305429Y219400
Y223000
X329929Y241500
X346404Y260000
X328000Y285000
X327000Y308000
X331000Y308018
X341500Y309500
X344429Y312000
X343929Y320700
X344929Y325500
X341351Y336434
X345929Y336500
X342500Y340000
X338500Y397500
X303545Y445840
X343095Y446200
X336375Y452870
X312925Y462560
X338985Y467405
X330555Y467500
X305055Y472500
X349815Y475550
X302555Y476000
X325873Y477006
X349575Y479503
X325854Y480606
X338595Y482590
X300112Y483783
X317195Y493280
X336445Y509330
X343688Y509533
X339140Y512500
X317255Y514170
X343555Y517000
X330491Y525490
X334055Y526000
X312773Y529878
X348255Y534500
X344655
X341055
X321555
X329695Y534650
X305255Y542600
X340715Y545840
X347213Y546700
X334555Y548500
X315725Y549790
X315135Y554980
X345500Y556500
X329055Y569500
X321780Y575000
X317758Y581297
X313000Y582000
X314930Y585500
X339888Y586388
X342500Y653000
X346402Y653004
X321500Y688000
X335500Y868000
X331829Y885500
X332129Y889371
X339500Y936500
X338000Y942000
X333500Y954000
X339500Y960000
X377464Y987493
X377250Y982250
X369200Y980252
X364396Y980109
X360024Y979100
X372500Y977918
X366878Y977500
X361000Y974000
X363614Y971524
X376000Y960000
X354000
X388500Y955250
X398250Y955000
X390000Y946500
X389838Y942300
X383500Y938500
X369500Y936500
X368000Y932000
X363000Y931500
X359000
X371000Y930000
X377000Y927500
X384000Y926500
X371100Y926000
X371938Y922438
X372300Y918749
X369341Y916117
X365500Y916000
X363480Y907783
X375500Y906000
X362000Y904500
X396500Y904000
X375500Y901500
X399500
X396330Y899705
X396600Y895855
X397600Y892000
X396500Y888500
X362210Y876200
X380000Y872000
X364000Y869500
X395500Y867000
X371000Y866500
X391000
X376041Y866041
X392500Y718500
X396000Y714500
X350000Y652878
X389000Y604000
X360500Y588500
X351815Y546880
X367555Y545500
X384046Y536546
X362555Y534500
X354055Y534000
X381500
X358797Y532258
X379000Y531000
X352095Y524040
X364055Y512000
X367022Y482783
X373555Y482500
X378255Y471840
X388885Y471100
X364015Y468450
X396055Y456500
X386055Y454500
X393055Y451000
X385463Y450948
X393055Y447400
X386755Y447300
X375055Y444500
X369555Y417500
X370275Y413540
X370575Y409952
X371710Y406535
X355055Y394000
Y389500
X357055Y385000
Y380500
X375805Y380250
X357055Y376500
X372055Y364000
X371555Y347500
X351929Y332500
X382455Y331870
X369555Y322500
X372055Y319500
X377855Y300110
X381500Y297000
X374000Y293500
X398385Y292540
X395104Y291056
X366600Y285800
X395450Y265400
X390100Y263600
X387500Y261000
X394929Y247000
X399500Y240500
X391000Y238500
X388000Y233500
X397900Y231800
X388149Y229780
X393429Y229500
X353300Y218400
X353929Y128500
X351429Y126500
X352500Y113000
X357500Y79500
Y75500
X352000Y66000
X390000Y13500
X385000
X355000Y4400
X350500
X369400
X364900
X360400
X414000Y8000
X438500Y9000
X448929Y99500
X433929Y100000
X430540Y108750
X418192Y114237
X421000Y231500
X409929Y245400
X420429Y246400
X439000Y254500
X433929Y264300
X424929Y264700
X428100Y266500
X440500Y267000
X422500Y271501
X419600Y282900
X444255Y283700
X439800Y284100
X416500Y284800
X408656Y291500
X419455Y293000
X401855Y293500
X405555
X435000Y294000
X439200Y294550
X430900
X416187Y294711
X412513Y294800
X432500Y301000
X429500Y311000
X401555Y318000
X406555Y320500
X436416Y357676
X403255Y425950
X432178Y798000
X425178
X444678Y798400
X438178Y798500
X431778Y802000
X425278
X444778Y802100
X438278
X418278Y828000
Y840000
X442278Y846000
X418278Y846500
Y854000
X418500Y857500
X404500Y877300
X437778Y883000
X431278
X444278
X410500Y885500
X431500Y886000
X443178
X437678
X432000Y933500
X414500Y948500
X418500
X422098Y948630
X403250Y949000
X408250Y949500
X405704Y952046
X400750Y952000
X414215Y952089
X410500Y954500
X413500Y957000
X416046Y959546
X430500Y962000
X420000Y964000
X416000
X410000Y983500
X413600
X410500Y987500
X401500Y994500
X425000
X483500Y907500
X488000Y904500
X472178Y886000
X482178
X460678
X451178
X468178
X473778Y883000
X460778
X450778
X467278
X480278
X457578Y879700
X498500Y867500
X497778Y847000
X459278Y846000
X455278
X451278
X467278
X497778Y843000
Y838500
X452978Y805400
X462778Y802100
X456278
X469278
X475778
X463178Y798500
X469178
X475678
X456178Y798000
X492555Y431250
X458685Y425710
X466655Y425340
X472055Y425000
X495555Y369500
X463945Y349700
X496155Y321700
X487612Y318606
X495103Y315952
X491257
X474755Y308300
X464200Y307838
X498855Y302851
X469155Y297800
X463371Y290371
X459500Y290100
X459055Y263500
X461100Y260050
X466700Y259400
X464055Y256500
X456000Y243500
X460000
X470000Y188500
X475216Y182917
X455054Y179475
X499629Y178400
X462679Y176900
X458429Y175590
X457429Y171500
X462500Y169000
X495929Y164500
X490100Y162100
X465600Y162000
X467600Y158400
X477929Y158000
X477900Y153600
X499390Y153500
X481429Y150000
X477291Y147500
X471000Y141000
X471429Y133500
X481929Y126500
X457500Y121000
X462700Y120800
X471290Y118361
X450929Y118000
X488500Y114200
X472990Y113350
X469000Y113000
X459429Y106000
X513200Y121450
X517679Y125750
X503929Y127500
X525679Y136250
X503929Y146500
X506429Y149500
X503500Y153500
X533000Y153800
X513000Y156500
X528500Y172000
X539714Y179150
X542500Y188500
X545000Y195000
X537479Y197875
X549926Y204000
X546916Y217641
X547746Y225303
X548000Y231000
X539073Y237300
X534500Y295500
X531590Y297620
X528500Y310000
X534629Y311171
X519706Y314000
X515860
X500607Y314200
X504453
X527002Y319359
X523348
X508500Y320000
X512000
X538614Y321000
X534960
X533502Y325500
X529848
X526500Y342969
Y346532
X520500Y347937
Y351500
X526500Y352969
Y356532
X520500Y358937
Y362500
X548000Y369500
X507355Y390800
X505922Y415371
X506163Y419973
X508100Y605500
X506000Y610000
X521500Y632500
X559500Y604500
X564215Y369339
X566430Y366500
X562555Y364500
X569555Y364000
X555935Y363000
X562055Y347500
X553155Y334300
X557061Y334194
X563555Y333000
X560253Y329500
X571555Y326000
X553555Y321000
X563704Y272000
X574000Y269000
X559971Y237753
X583204Y236805
X564631Y234356
X569322Y234220
X573179Y233535
X577119Y233139
X580709Y232091
X575425Y228505
X569000Y217000
X550075Y215913
X553675
X557275Y214918
X569127Y213100
X559961Y209419
X583325Y208500
X571461Y207887
X568158Y206455
X564583Y206028
X583500Y204500
X576650
X587175Y202525
X591413Y199087
X575500Y198400
X585325Y198000
X563100Y194000
X559500
X555500
X572000Y189000
X550500Y188000
X560500Y186000
X571398Y183602
X561429Y174441
X577000Y58000
X646500Y101000
X619876Y195000
X645457Y303250
X629712
X633578
X649323
X617828
X613962
X647500Y425500
X647125Y429375
X642800Y433587
X640500Y444500
X636500Y444800
X641500Y449500
X635325Y457500
X645500Y459500
X641625Y465375
X628250Y570200
X623500Y576500
X647252
X628524Y591976
X622500Y608500
X667000Y969700
X676500Y967750
X672000
X666750Y961550
X697250Y876750
X679000Y865050
X673500Y864000
X671500Y861000
X670474Y808700
X691300Y807300
X678468Y805284
X687968Y781784
X677500Y773500
X698818Y759350
X682968Y758284
X687968Y755284
X691000Y704500
X677500Y699000
X674688Y696751
X680000Y640000
X677500Y612000
X663500Y610500
X688500Y606000
X683000Y603950
X669000Y579000
X673300
X654500Y494000
X654300Y490300
X667056Y475500
X673010Y474436
X677500Y472500
X669462
X656162Y472338
X690000Y460500
X672500
X681000
X663500
X667500Y458500
X676500
X681000Y456000
X663500
X672500
X667500Y454000
X676500
X663500Y452000
X672500
X681000
X660000Y443500
X669025Y441725
X687500Y440500
X660500Y436538
X652714Y428214
X665073Y303250
X661207
X678055Y258500
X687055
X683055
X667748Y104000
X674358Y103170
X662248Y101000
X650500
X674469Y99380
X684197Y74703
X686000Y62000
X684861Y58584
X685519Y55019
X676748Y52000
X747800Y50200
X716034Y53966
X728966
X716466Y65466
X728966
X740500Y75000
X720216Y82138
X711216Y82402
X706716Y82448
X715716Y82652
X721716Y112784
Y116784
X717716Y121284
X725716
X721716
X729716
X713716
X721716Y125284
Y129284
X745500Y145000
X711500Y179400
X733498Y180750
X733000Y193000
X721200Y205800
X747000Y210000
X728100Y213800
X706055Y258500
X710055
X714055
X725000Y452300
X749750Y454000
X732500Y455500
X736000Y464500
X728500Y482500
X732500Y485500
X730000Y536500
X734500Y547500
X734462Y553538
X717036Y563783
X720700Y564200
X729900Y568500
X733500
X705900Y569200
X746750Y571750
X705500Y575600
X748000Y579500
X741500Y582450
X737000Y583640
X709750Y585200
X719918Y754734
X733268Y757984
X740768Y763984
X735500Y771984
X723168Y774984
X715118Y776134
X735000Y780500
X702918Y782734
X703328Y800144
X733768Y800734
X722000Y808500
X736000Y810500
X717468Y810784
X727468Y819284
X712500Y859750
X720500Y860000
X716250Y860250
X710750Y863250
X714000Y867500
X741050Y869500
X733440Y875560
X745400Y877600
X740000Y886000
X714500Y891000
X704000Y892500
X737290Y903000
X733000Y969700
X749500Y974300
X785500Y969700
X776750Y964750
X794500Y897000
X757000Y896400
X785000Y892000
X774500Y890500
X781000Y877000
X766750Y849250
X782750Y845750
X763500Y839500
X768000Y833000
X791500Y783500
X787500
X757500Y743500
X768000Y728000
X755000Y727500
X794000Y723500
X760500Y707950
X798000Y706000
X779500Y705000
X783746Y692754
X771000Y689500
X770646Y685354
X784804Y673304
X760125Y666875
X785500Y666500
X783500Y649000
X767000Y648500
X763000Y648000
X766000Y635000
X786500Y575688
X786032Y570468
X765009Y563491
X791000Y562000
X790000Y554500
X790600Y547600
X751484Y540600
X774500Y489500
X760500
X755300Y489300
X784274Y486274
X788774Y482774
X796074Y479000
X772024Y478976
X776000Y478828
X771000Y464000
X779000Y458000
X758500Y457000
X788800Y453000
X784900
X788600Y449300
X784800
X798000Y400500
X773500Y326000
X771447Y303250
X759563
X755697
X775313
X787192
X791058
X789500Y235837
X775748Y188500
X765116Y187659
X796000Y167600
X795500Y163408
X770900Y144300
X770500Y136000
X757200Y103100
X760600Y94500
X761000Y88500
Y82500
X762250Y71000
X754500Y67500
X832000Y137500
X826198Y239950
X818000Y240900
X842555Y262000
X833555
X838055Y262500
X847055
X802942Y303250
X806808
X844410Y346360
X821100Y348480
X847500Y352000
X821100Y352480
X808500Y363500
X847000Y396500
Y401500
X842000
X832500Y404000
X847000Y406500
X825500Y411100
X811000Y430500
X806274Y434726
X826500Y436000
X826000Y465078
X814500Y472500
X823500Y480000
Y556500
X819500Y564000
X815900
X802500Y579500
X831000Y598500
X833500Y613000
X849500Y622000
X846250Y642250
X803500Y655000
X846500Y710000
X835000Y719000
X842500Y719500
X802000Y724000
X810000Y735500
X826500Y743000
X821250Y845750
X814000Y849500
X810500Y851000
X839250Y854500
X826060Y863440
X845500Y865000
X805250Y865750
X801750Y867500
X819000Y868500
X824560Y868560
X852600Y868500
X860500Y734000
X852500Y710500
X881000Y710000
X878500Y695500
X865500Y690500
X860718Y683684
X870500Y665060
X867500Y655200
X861250Y649250
X854000Y640500
X871000Y639500
X884200Y636500
X872000Y636000
X876000Y631700
X859500Y629500
X862500Y621250
X877500Y612500
X857500Y485500
X871500Y484000
X877000Y479500
X874450Y463500
X870500Y448000
Y444000
X882700Y443100
X893600
X886300
X889900
X885000Y438700
X854000Y436500
X876000Y435500
X893500Y427000
X877000Y409500
X878000Y404500
X852000Y401500
X887940Y380200
X868820Y363880
X863820
X874910Y360160
X887950Y359730
X879510Y355410
X854820Y352380
X884120Y351630
X850540Y346070
X888750Y324660
X877860Y316330
X898000Y316000
X899000Y312500
X865055Y262500
X851555
X856055
X860555
X870100Y237500
X860400Y231000
X869544Y226000
X872000Y75500
X873000Y68500
X923000Y51500
X903480Y324230
X939500Y352000
X936000Y373500
X924465Y388465
X904600Y406600
X944000Y434000
X934000Y448700
X918420Y449130
X936030Y457540
X907000Y465050
X903075Y472000
X937000Y489000
X935400Y597300
X917000Y752500
X989000Y757150
X970750Y703000
X975000Y701000
X989000Y659500
X998500Y591500
X957500Y585500
X961500
X978000Y554000
X982500Y549500
X977000Y547500
X994500Y543800
X990500Y536500
X992000Y505500
X994500Y491000
X961700Y477500
X992690Y466750
X996910Y466560
X998000Y461500
X970382Y455872
X973015Y453416
X968085Y452065
X982075Y439500
X988900Y434800
X965000Y364500
X964000Y354000
X959500Y351688
X953500Y348927
X965500Y260500
X963500Y256000
X962000Y251500
X980078Y204578
X980490Y198827
X980960Y195257
X957990Y191064
X988660Y190500
X958500Y187500
X996500Y167000
X989000Y66500
X1012000Y43000
X1003000Y59500
X1016500Y87500
X1033500Y118000
Y124000
X1020500Y124500
X1025500Y129500
X1037085Y137000
X1041485Y137409
X1045031Y138031
X1020500Y142000
X1048968Y150784
X1039500Y151000
X1044000Y153000
X1023000Y155000
X1034000
X1048968Y155284
X1039468
X1044000Y157500
X1048968Y159284
X1039500Y159500
X1028000Y164500
X1023600Y173000
X1040000Y182000
X1045968Y185500
X1036000Y199500
X1036019Y203177
X1035922Y209578
X1031524Y218476
X1017274Y219274
X1037500Y225500
X1033900
X1027426Y346500
X1023000Y347000
X1031000Y348500
Y355950
X1030000Y403500
X1014000Y487000
X1007500Y487500
X1003422Y490578
X1007500Y507000
X1016500Y519500
X1002500Y520000
X1008500Y533400
Y543700
X1013500Y559000
X1016900Y561000
X1040000Y579000
X1036500Y581500
X1017982Y585018
X1021000Y588500
X1035000Y594500
X1038000Y604000
Y635000
X1045500Y639500
X1046000Y644000
X1042450Y648500
X1025500Y657000
X1042400Y684500
X1041410Y704224
X1038500Y706500
X1041410Y708804
X1023500Y727000
X1037000Y734000
X1024387Y738230
X1040208Y745020
X1044000Y763940
X1001000Y771500
X1035000Y800000
Y804500
X1021468Y866968
X1032600Y867657
X1007032Y879968
X1035000Y880500
X1031500Y884500
X1035216Y884468
X1039000Y884500
X1035000Y888500
X1011966Y893534
X1032657Y901500
X1007532Y902468
X1020282Y911218
X1027716Y914784
X1032200Y921500
X1042500Y930000
X1083200Y956500
X1077000Y943075
X1097423Y906546
X1093500Y905500
X1093468Y896968
X1085468Y895968
X1099623Y869123
X1089000Y867284
X1092718Y859984
X1097500Y849000
X1083700Y835725
X1098500Y823344
X1095500Y812000
X1093000Y791000
X1097500Y784500
X1063000Y780000
X1098000Y775000
X1052500Y773350
X1070098Y764500
X1077500Y759000
X1084000Y748099
X1056350Y748000
X1077500Y745374
X1072000Y743500
X1084300Y741874
X1071500Y739000
X1054000Y735000
X1073000Y730834
X1087600Y727029
X1094853Y726853
X1073000Y726444
X1090257Y724253
X1073384Y722384
X1059800Y719740
X1066000Y717000
X1074288Y715534
X1052648Y712724
X1074148Y711624
X1052500Y709000
X1074600Y707724
X1052678Y704084
X1074000Y703500
X1052500Y700000
X1074000Y699500
X1054500Y697000
X1074500Y694754
X1052500Y693000
X1091000Y692519
X1074389Y691155
X1074426Y687255
X1068500Y687000
X1074000Y683000
X1058350Y681450
X1068500Y677000
X1074000
X1073500Y672000
X1085000Y661000
X1054900Y660900
X1058500
X1094500Y657500
X1050092Y655052
X1070000Y650725
X1093500Y640000
X1073000Y637500
X1074500Y627500
X1053500Y620500
X1056000Y604000
X1058000Y599500
X1071500Y589000
X1098000Y562000
X1059000Y558190
X1086000Y556000
X1091425Y551425
X1081000Y548000
X1084599Y544520
X1081000Y544400
X1080000Y520000
X1089000Y508500
X1068300Y488700
X1098500Y465000
X1078500Y464000
X1092500Y461500
X1061200Y399000
X1060766Y395426
X1055000Y219284
X1061000Y211500
X1072500Y208924
X1060000Y207500
X1084500Y202500
X1056500Y194000
X1080300Y191000
X1052500Y187500
X1074500Y185500
X1066500
X1060509Y177126
X1060900Y173534
X1058000Y159500
X1053500Y157500
X1057968Y155284
X1053500Y153000
X1058000Y150500
X1072000Y136000
X1098000Y126500
X1090028
X1086000
X1093894
X1069000Y124500
X1068500Y118500
X1077500Y107500
X1077250Y102000
X1077500Y97000
X1088000Y85500
X1055500Y80000
X1064000
X1068000
X1059500
X1068000Y76000
X1059500
X1055500
X1064000
X1071000Y71000
X1123000Y250500
X1146000Y258500
X1146500Y267000
Y275500
X1110318Y275600
X1145800Y282284
X1120600Y282300
X1128000Y288500
X1132300Y288800
X1136100Y288900
X1136450Y294650
X1142640Y359860
X1146640
X1130000Y361500
X1124327Y465391
X1111500Y517500
X1123500Y521500
X1128149Y525261
X1130928Y527550
X1147500Y542000
X1143500
X1100575Y559075
X1136075
X1132000Y562000
X1125600Y570600
X1145900Y579800
X1107500Y580000
X1141100Y585400
X1119487Y588088
X1140500Y589000
X1122353Y590268
X1114883Y591925
X1136500Y592500
X1132222Y593278
X1139632Y594441
X1135000Y597000
X1125000Y603050
X1106000Y605500
Y609500
X1134000Y613500
X1126000Y618000
X1147000Y619000
X1121500Y621600
X1126000Y627329
X1130490Y627436
X1125041Y631000
X1131000
X1111500Y718500
X1124000Y729000
X1120500Y729500
X1147400Y729900
X1128430Y749640
X1126210Y752810
X1132960Y752950
X1107000Y757500
Y763000
X1123200Y783900
X1126642Y785505
X1110300Y790000
X1111834Y813334
X1130030Y820000
X1121000Y823500
X1113500Y824500
X1111000Y836000
X1107160Y843160
X1118034Y847034
X1113768
X1135468Y854032
X1116468Y865784
X1131275Y867725
X1112468Y870284
X1120468
X1116468
Y874284
X1118500Y886000
X1114500
X1103000Y888300
X1162000Y960625
X1181500Y949000
X1196000Y874500
X1177000Y860000
X1164500Y857500
X1188875Y856625
X1169000Y856000
X1196000Y847500
X1198718Y800782
X1173200Y789500
X1153500Y784190
X1184750Y781000
X1188500Y773000
X1184500Y772782
X1184975Y767500
X1190000
X1194000Y764500
X1188000Y762500
X1192038Y761481
X1160333Y753600
X1184500Y749500
X1196500Y745500
X1192500
X1196500Y736687
X1189890Y684053
X1199551Y683968
X1192937Y683911
X1195937Y683849
X1191000Y667000
X1197500Y665500
X1191000Y663000
X1193804Y657175
X1178500Y653100
X1154847Y630908
X1159075Y630600
X1164500Y628723
X1183000Y628000
X1156377Y627623
X1177100Y624750
X1184956Y619272
X1186000Y615500
X1169075Y613500
X1165476Y613393
X1165672Y609672
X1152500Y608500
X1196000Y605800
X1181350Y595450
X1155000Y594500
X1154000Y589000
X1179934Y567000
X1173500Y554000
X1185500Y548075
X1161000Y541500
X1189000Y533825
X1197675Y533125
X1194564Y530936
X1191000Y528000
X1151500Y522000
X1155500Y450758
X1151500Y449000
X1155500Y446892
X1195000Y428000
X1173500Y422500
X1189000Y421500
X1166500Y415500
X1187500Y411000
X1197000Y409500
X1182500Y407000
X1174500Y404000
X1164000Y397000
X1168000Y390250
X1176500Y383500
X1197000Y372500
X1155400Y371500
X1175125Y370000
X1157700Y368500
X1174500Y366000
X1160058Y364558
X1157480Y361620
X1161530Y360430
X1150640Y359860
X1182000Y357000
X1178000Y356500
X1174400
X1184000Y351500
X1198000Y348000
X1196075Y344588
X1199685
X1192000Y344500
X1175000Y327000
X1167000Y326450
X1169515Y323716
X1173125
X1167000Y321000
X1174752Y320504
X1160000Y318500
X1152500
X1156100Y316405
Y312795
X1152500Y311000
X1168076Y310046
X1158000Y309500
X1165000Y308175
Y304565
X1168000Y302500
X1196334Y290561
X1185283Y290513
X1169777Y290125
X1173777
X1177500Y290000
X1166000
X1192743Y289800
X1188877
X1153700Y267700
X1151000Y264500
X1162468Y257968
X1180677Y256500
X1181427Y251500
X1188000Y248500
X1166000Y232000
X1171000
X1186500
X1239000Y190500
X1208500Y202000
X1239500Y204000
X1240000Y209449
X1209000Y212500
X1239500Y214000
X1208000Y231000
X1207500Y239500
X1201922Y248500
X1239000Y251500
X1202177Y260000
X1241777Y265700
X1208000Y271499
X1241377Y274900
X1208500Y283500
X1238500Y290000
X1208000Y297638
X1239000Y302437
X1208000Y309000
X1238500Y316500
X1208500Y321500
X1238500Y325985
X1206500Y330000
X1239000Y338900
X1203500Y345000
X1208500Y346400
X1239000Y352800
X1208500Y359000
X1239500Y366000
X1208000Y371000
X1234177Y379500
X1210800Y379700
X1216000Y390000
X1209500Y404500
X1243000Y431500
X1212500Y436000
X1209000Y438500
X1234500Y439000
X1248250Y439250
X1216500Y439500
X1243000Y446650
X1217000Y452500
X1242000Y459000
X1247800Y472750
X1246750Y476250
X1227500Y500500
Y504246
X1210000Y507500
X1214450Y509000
X1249000Y509500
X1220500Y513000
X1213100Y514000
X1209500
X1249251Y528688
X1229500Y533000
X1201500Y535000
X1210000Y536800
X1206400
X1231632Y537000
X1221500Y539500
X1240000Y542900
Y546500
X1235482Y546982
X1200500Y547925
X1240173Y550327
X1233000Y554502
X1209500Y561910
X1219200Y564600
X1205240Y568760
X1215500Y605300
X1207700Y605500
X1208500Y623000
X1241000Y631500
X1221500Y633000
X1204500Y659500
X1239500Y671000
X1237500Y675500
X1231450Y677500
X1235000Y682000
X1203181Y683968
X1206781Y684003
X1213598Y699164
X1216000Y702500
X1225500Y714500
X1229000Y716000
Y719600
Y726500
X1244371Y733129
X1210500Y733500
X1241000Y734500
X1236500Y737925
X1232000Y738000
X1229000Y740000
X1243000Y743000
X1234000Y747500
X1230219Y747469
X1213500Y756000
X1206500Y757000
X1224500Y757500
X1201968
X1240016Y761500
X1238000Y764500
X1221000Y764750
X1249500Y765500
X1231000Y768500
X1248950Y769500
X1228547Y772547
X1248500Y775500
X1228547Y778453
X1212840Y781000
X1248950Y782450
X1233000Y782500
X1243953Y789000
X1240045Y788957
X1238047Y791953
X1241984Y796000
X1223500Y798500
X1202218Y811282
X1235258Y820758
X1245650Y821850
X1223000Y826500
X1240660Y829000
X1218500Y834500
X1230500Y841000
X1229807Y847000
X1211000Y847500
X1204000Y862000
X1217250Y862250
X1208940Y874560
X1211500Y882500
X1298034Y907034
X1264000Y853000
X1269500Y835000
X1296500Y830782
X1257950Y809250
X1267500Y783000
Y779000
X1253500Y778465
X1279000Y746575
X1281500Y713000
X1284490Y710936
X1262500Y699825
X1267500Y684878
X1259000Y678950
X1263121Y678621
X1282300Y678000
X1267500Y675000
X1262300Y670700
X1275885Y670525
X1282500Y669561
X1289500Y669000
X1273702Y667662
X1291500Y666000
X1266000Y665600
X1297500Y665000
X1257100Y664300
X1281268Y661780
X1265000Y661000
Y657000
X1268805Y655405
X1286500Y652500
X1265500
X1265000Y647500
X1282500Y645000
X1272451Y642500
X1299000Y641500
X1272502Y638900
X1296000Y638500
X1290500Y635500
X1257500
X1294000Y628000
X1284825Y621500
X1279340Y618660
X1266500Y617500
X1271000
X1255000Y609300
X1274500Y606000
X1278500Y603500
X1282500Y598000
X1289570Y597430
X1288335Y594048
X1293500Y593000
X1287482Y590500
X1294000Y587500
X1285557Y585000
X1271000Y573500
X1286500Y569000
X1271000Y568500
X1250500Y567000
X1297500Y562000
X1258000Y555400
X1263500Y550000
X1260500Y546400
X1291300Y540900
X1251500Y531500
X1285700Y529700
X1293960Y528740
X1294600Y524200
X1253000Y511000
X1257468Y478500
X1270000Y477000
X1272500Y466600
X1250450Y462000
X1278500Y448500
X1260000
X1269468Y448284
X1274000Y447000
X1264500Y446500
X1259968Y444284
X1269468
X1278500Y444000
X1264500Y442000
X1274000
X1260000Y440000
X1269468Y439784
X1278500Y439500
X1265000Y426500
X1250000Y422000
X1280000Y420500
X1289000Y415500
X1280500Y404550
X1292500Y402000
X1280500Y338000
X1250158Y326463
X1253177Y324500
Y320500
X1253500Y316500
X1253477Y312800
X1257000Y311000
X1253577Y308800
X1253500Y305000
X1261006Y303543
X1260577Y299968
Y296102
X1261000Y292500
X1295500Y291500
X1252564Y290566
X1250677Y287500
Y283500
X1254203Y282770
X1263000Y278500
X1251700Y274000
X1254944Y272433
Y268567
X1251500Y266500
X1264500Y260000
X1262558Y254942
X1256000Y252000
X1261677Y245500
Y241500
X1260677Y237000
X1299500Y236000
X1276500Y234000
X1264177Y233500
X1267677Y232500
X1261000Y211500
X1265000
X1261000Y207500
X1258000Y205000
X1265000Y174000
Y169000
X1261000Y166500
X1256500
X1279500Y150500
X1290874Y34376
X1257000Y33000
X1306000Y43000
X1347000Y48000
X1309500Y51000
X1342500
X1339000Y54000
X1333100Y58600
X1347000Y88000
X1343500Y112000
X1349500
X1347500Y116000
X1331000Y120000
X1336500Y270874
X1339000Y274000
X1324000Y290500
X1304050Y296500
X1322500Y299000
X1339500Y305500
X1308000Y311000
X1312750Y314000
X1322000Y318500
X1307500Y320500
X1306000Y329000
Y334500
X1317000Y336000
X1322500Y337000
X1306000Y338500
X1341873Y344873
X1344000Y434500
X1340200
X1311000Y435000
X1340200Y438300
X1343900Y438500
X1330500Y441000
X1335000Y443250
X1323500Y452500
X1332000Y459250
X1311000Y463500
X1343000Y466500
X1302000Y475000
X1304700Y536000
X1334500Y557000
X1302500Y559500
X1307000Y573412
X1335317Y575412
X1307900Y577412
X1306617Y587512
X1344617Y588712
X1306817Y592412
X1344617Y593412
X1349317
X1326617Y594412
X1308817Y595412
X1325950Y599000
X1347617Y610412
X1342648Y612412
X1310500Y625000
X1323117Y626412
X1329317Y626512
X1346617Y626912
X1342367Y627662
X1349817Y628612
X1334500Y636000
X1312000Y645784
X1328000Y649000
X1311000Y651900
X1311100Y656400
X1310425Y660062
X1304400Y661400
X1329468Y666468
X1334500Y669000
X1312115Y672000
X1311000Y677284
X1328968Y679684
X1333468Y680000
X1311700Y681500
X1311300Y687500
X1323500Y702000
X1322000Y705500
X1313500Y710000
X1305000Y739750
X1308100Y748200
X1314284Y782500
X1306000
X1318784Y793716
X1325250Y834250
X1304500Y838000
X1312500
X1300784Y838716
X1316500Y839000
X1318113Y846371
X1317000Y850500
X1312000
X1305000
X1303750Y862250
X1307468Y884532
X1321466Y907034
X1314500Y921500
X1353517Y627512
X1363100Y627000
X1357300Y617700
X1360200Y614800
X1353117Y610412
X1364617Y592912
X1356817Y579012
X1367617Y570012
X1360817Y557812
X1369617Y557012
X1355500Y556500
X1353500Y466500
X1374500Y462800
X1362500Y459000
X1351000Y455750
X1368000Y450500
X1353000Y402000
Y390000
X1370500Y356500
X1384500Y331500
X1375500Y328000
X1379500Y314000
X1350084Y296500
X1381500Y292000
X1376000
X1358500Y288916
X1350000Y276500
X1354500Y276000
X1384500Y274500
X1379500
X1390004Y122600
X1369720Y106365
X1390004Y106000
X1352000Y85500
T03
X8590Y318590
X4500Y329297
Y349297
Y369297
X20000Y380000
X4500Y389297
Y409297
Y429297
X20000Y440000
X4500Y449297
X20000Y460000
X4500Y469297
X20000Y480000
X4500Y489297
X20000Y500000
X4500Y509297
Y529297
Y549297
Y569297
Y589297
Y609297
Y629297
Y649297
Y669297
Y689297
Y709297
Y729297
Y749297
Y769297
Y789297
Y809297
Y829297
Y849297
Y869297
Y889297
Y909297
Y929297
Y949297
Y969297
X75000Y975000
X55000
X25000Y980000
X45000
X65000
X95000Y975000
X177500Y939500
X162000
X167500
X156500
X172500
X140000Y740000
Y720000
X178000Y590000
X168000Y580000
Y575000
X121000Y545500
X146364Y296000
X255800Y179600
X261400Y179800
X258800Y184200
X256300Y188800
X261500Y188900
X259000Y206000
X262500Y208500
X259000Y211000
X260000Y260000
X222000Y703500
X207100Y703600
X260000Y760000
X220000
X180000
X224000Y875000
X225500Y879500
X261000Y883000
X252000
X243000
X247500
X256500
X265500
X225000Y920500
X232000Y921000
X188000Y939500
X182000
X199500
X193500
X233468Y957284
X252000Y957500
X227500
X246968Y957784
X239968
X227500Y963500
X252500
X233468Y963784
X239968
X246968
X268000Y969500
X262178Y976000
X261178Y981040
X206000Y982000
X226000
X246000
X348678Y996000
X341178
X358268Y995500
X301178
X317178
X324678
X332678
X309678
X285678
X293178
X277500Y969500
X272500
X278500Y965000
X355500Y614000
Y608500
X335645Y445630
X357661Y434216
X322429Y349300
X286000Y336000
X307429
X311429Y334500
X307429Y331500
X285500Y330000
X352429Y279000
X357929Y277000
X311500Y272000
X316000Y271500
X351929Y266000
X310929Y257500
X315929
Y253000
X281800Y188500
X285600Y186100
X281800Y183700
X285800Y180800
X281900Y178500
X296000Y105000
X306000
X301000
X337500Y102000
X321000Y61500
Y57000
Y52500
Y48000
Y42500
X349000Y38500
X330500
X321000Y38000
X330500Y33500
X321000
X349000
X321000Y29000
X336000Y27000
X344000
X324000Y24000
Y19500
Y15000
X316000Y11000
X320500
X299500Y5500
X389300Y20100
X393800
X398300
X384800
X389300Y25100
X384800
X398300
X393800
X384900Y30400
X393900
X398400
X389400
X391000Y35500
X400000
X395500
X398000Y39500
X370000Y51000
X386000Y53000
X381500
X370000Y55500
X381500Y58000
X370000Y60000
X362500Y64000
X370500Y72100
X366000Y277500
X445395Y317610
X364055Y428500
X361055Y431500
X403155Y437600
X369500Y608500
X362500
X376500
Y614000
X369500
X362500
X406500Y713500
X431000
X412000Y724000
X431000
X422500Y764500
X409500Y775500
X378500Y812000
Y824500
X432678Y827300
X430778Y864000
X377953Y995725
X435678Y996000
X443178
X389763Y996085
X536678Y996000
X450178
X458678
X466178
X489678Y995500
X474178
X513678
X498178
X482178
X505678
X530083
X521178
X499000Y883000
X495000
X501000Y876000
X482278Y867500
X456278Y866500
X482778Y832000
X453878Y824900
X490500Y800000
X502500
X477500Y715000
X491500
X504500
X516500Y556000
X516655Y548900
X521055
X526055
Y544000
X521055
X516555Y543500
Y539000
X521055Y538500
X526055
X516555Y533500
X526055
X521055
X526000Y529000
X516555Y528500
X521055
X526000Y524500
X521000Y524000
X482429Y139000
X519929Y135500
X516000Y134000
X467000Y118500
X560000Y20000
X591000Y253500
X595500
Y258000
X591000
Y262500
X586000
Y267000
X615000Y333000
X610500
X620500
X616500Y341500
X611500
X621500
X606000
X609000Y345500
X613500
X586200Y378500
X582000
X581950Y383000
X590500
X586150
Y396000
X590500
X581950
Y409500
X590500
X586150
X610000Y415500
X614200
X610000Y422000
X614200
X581950Y423500
X586150
X590500
X610000Y428500
X614200
X587000Y431500
X578500
X582700
X610000Y434000
X614500
X614300Y439500
X582200
X578000
X586500
X610100
X567500Y453000
X563000
Y457500
X567500
Y462000
X563000
X613500Y465800
X626500
X608000
X620000
X602500Y465900
X563000Y466500
X567500
X620000Y470000
X626500
X613500
X602500Y470100
X608000Y470300
X601000Y543000
X626500Y557350
X599500Y648500
X593500
X599500Y654000
X593500
Y659500
X599500
X616500Y714500
X604500
X613500Y744500
Y759000
X603000Y778500
X609500
X603000Y785000
X620500Y848500
X609000Y870000
X604000Y877500
X609211Y877611
X606000Y918500
X598178Y983500
X584678Y994500
X576678Y996000
X569178
X560678
X682500Y917500
X630500Y912000
X656500Y906000
X657500Y827000
X633500Y749500
X634000Y734500
X694000Y514000
Y507500
Y500500
Y492000
Y483500
X645500Y481000
X693500Y472000
X690500Y468000
X632500Y436500
X637000
Y431500
X632500
X634500Y427000
X670500Y414000
X638500Y409000
X646500Y408500
X651500
X670000Y395000
X707000Y385000
X711500
X707000Y378000
X711500
X708500Y371000
X630500Y368500
X653500
X642000
X659500
X647500
X665000
X637500Y367900
X708500Y365000
X705500Y352500
X707000Y340500
X642000Y335000
X668000Y334000
X673500
X662000
X639000Y332000
X719500Y185600
X718216Y156520
X709216
X713716
X704716
X700216Y156368
X685000Y150500
X690966Y142028
X703053Y133568
X685898Y133380
X698500Y132500
X670522Y130200
X682418Y129980
X701828Y129550
X697248Y128000
X660000Y120000
X701949Y118331
X670998Y116010
X650000Y110000
X670454Y94544
X674666Y82002
X730748Y99500
X800000Y100000
X740000Y109534
X760522Y116784
X770000Y123500
X746716Y130238
X750916Y130272
X732248Y140000
X727248Y141500
X736000Y142000
X722716Y156520
X727216
X731716Y156500
X725000Y189000
X782400Y339400
X777500Y339500
X773000
X777500Y351000
X782500
X792000Y356500
X782600Y411000
X761500Y431000
X756500
X751500
X766000
X757000Y435500
X752100Y435600
X761600
X776468Y447600
X757802Y474000
X801500Y573000
X770000Y677000
X740000Y681000
X770000Y681500
X740500Y755000
X739900Y760000
X767000Y845000
X720000Y849000
X721900Y852750
X720000Y905000
X773000Y917000
Y921500
Y927000
X767500
X766600Y958500
X771000
X762100Y958600
X767100Y963500
X771500
X762600Y963600
X771400Y968900
X767000
X762500Y969000
X800500Y977500
X794500
X800500Y982000
X794500
X854500Y783000
X850000
X854500Y778000
X850000
X820500Y765500
Y754000
X858500Y656500
X895000Y617500
X889000Y617000
X848600Y517100
X843100Y517000
X848700Y512900
X843200Y512800
X848800Y508000
X843300Y507900
X819000Y473000
X899000Y410500
X894000
X899000Y405500
X894000
X884000Y396500
X879500
X829500Y385500
Y380000
X842000Y377500
X829500Y373500
X842000Y372000
Y367000
X813500
X846500Y362000
X818500Y361600
X837000Y361500
X828500
X878500Y294178
X875500Y290500
X879736Y290000
X870000Y160000
X890000Y140000
X810000Y120000
X895000Y96000
X899500Y92500
X910000Y160000
X966000Y209500
X961000Y212500
X930500Y219000
X936500
X930500Y225500
X936500
Y232000
X930500
X981000Y386500
X985000Y388000
X980500Y391000
X984500Y392500
X943500Y488000
X963500
Y536500
X930500
X958000Y654500
X963500
X974500Y655100
X969000
Y659500
X963500
X974500
X958000
X980000Y725500
X965000
X915000Y805000
Y825000
Y845000
Y865000
Y885000
Y905000
Y925000
Y945000
Y965000
X1075000Y970000
X1055000
X1035000
X1060000Y929500
X1058000Y902500
Y896000
Y889500
X1051000Y888500
X1020500Y887000
X1051000Y883600
X1020500Y882500
X1035500Y830000
X1040000
X1044500Y825500
X1049000
X1053400
X1040000
X1035500
X1000500Y667500
X990000
X1011500Y648000
Y642000
X1079000Y434000
X1079100Y429000
X1060600Y303150
X1056100Y303200
X1059900Y295200
X1046200Y294200
X1027700
X1033200
X1039700
X1059800Y290600
X1027500Y290000
X1033000
X1039500
X1046000
X1060500Y282500
X1013000
X1012900Y275300
X1031800Y248800
X1036300
X1027500Y248500
X1057000Y229500
X1053000Y228000
X1056716Y224500
X1065000Y154000
X1077500Y150000
X1032000Y110000
Y103500
Y97000
Y90000
X1013500Y84000
X1009000
X1004500
X1032000Y82500
X1016500Y75500
X1021000
X1034500Y51500
X1022500
X1028000
X1007000Y12000
X1080500Y153500
X1084988Y154203
X1085150Y158400
X1100000Y180000
X1086000Y187500
Y192500
X1161500Y222000
X1166500
X1134000Y229000
X1128500
X1165000Y242000
X1160500
Y246500
X1165000
X1169000Y398000
X1105000Y400500
X1085000Y434000
X1101500Y461500
X1135500Y502500
X1129000
X1141000
X1123500
X1135500Y507500
X1129000
X1141000
X1123500
X1106600Y753000
X1097500Y762500
X1102500
X1093000Y766500
X1097500Y767400
X1102500
X1097500Y797500
X1091500Y846500
X1114500Y855500
X1119000
X1164500Y890000
X1158000
X1144500
X1152000
X1137000
X1145000Y970000
X1125000
X1105000
X1195000
X1215000
X1175000
X1181500Y820500
X1177000
X1182000Y816000
X1195920Y753700
X1216500Y710125
X1217000Y537000
X1188500Y500000
X1173100Y499200
X1194000Y493000
X1189500Y492900
Y488500
X1194000
X1189500Y484000
X1194000
X1170500Y461000
X1195000Y422500
X1171000Y394000
X1246000Y263500
X1239500Y227500
X1244000
X1194900Y226600
X1203300
X1199100
X1207500Y225000
X1242000Y223500
X1176000Y222000
X1171000
X1241000Y219000
X1204000Y215000
Y210500
X1208500Y207000
X1204000Y206000
X1203500Y198000
X1208000
X1203500Y193800
X1208000
X1240700Y184000
X1240800Y179800
X1240700Y175500
Y171200
X1240600Y167000
X1249300Y166000
X1324500Y341000
X1338000Y341100
X1329000
X1333500
X1324500Y345400
X1329000Y345500
X1333500
X1338000
X1323000Y368000
X1327500
X1332000
X1318000Y369500
X1323000Y372400
X1327500
X1332000
X1318000Y375500
Y381500
X1330000Y428000
X1287500
X1331500Y432500
X1292500Y441000
X1288000Y442000
X1281000Y475000
X1276500
X1285500
X1293500
X1263000Y717000
X1277500Y757500
X1303000Y771500
X1308500
X1314000
X1277500Y778500
X1354500Y703500
X1351000Y677000
X1355000Y674500
X1351000Y672000
X1354500Y669000
X1357500Y635500
X1360000Y631500
X1355500Y631000
X1358000Y626000
X1360500Y486500
X1354500
Y480500
X1360500
Y475000
X1354500
X1372500Y415000
X1374500Y402000
Y395000
X1377000Y390000
Y384000
Y379000
X1378500Y374500
Y370000
Y365000
Y360000
X1358500Y351000
X1354000
Y346500
X1358500
X1366000Y264000
X1371500
X1366000Y259500
X1371500
Y254000
X1366000
T04
X545079Y290355
X549014Y298230
X552954Y290355
X556889Y298230
X560829Y290355
X564764Y298230
X568699Y290355
X572639Y298230
X576574Y290355
X580514Y298230
X584449Y290355
X588384Y298230
X592324Y290355
X596259Y298230
X600199Y290355
X604134Y298230
X608069Y290355
X612009Y298230
X615944Y290355
X619884Y298230
X623819Y290355
X627754Y298230
X631694Y290355
X635629Y298230
X639569Y290355
X643504Y298230
X647439Y290355
X651379Y298230
X655314Y290355
X659254Y298230
X663189Y290355
X667124Y298230
X671064Y290355
X674999Y298230
X678939Y290355
X682874Y298230
X686809Y290355
X690749Y298230
X694684Y290355
X698624Y298230
X702559Y290355
X706494Y298230
X710434Y290355
X714369Y298230
X718309Y290355
X722244Y298230
X726179Y290355
X730119Y298230
X734054Y290355
X737994Y298230
X741929Y290355
X745864Y298230
X749804Y290355
X753739Y298230
X757679Y290355
X761614Y298230
X765549Y290355
X769489Y298230
X773424Y290355
X777364Y298230
X781299Y290355
X785234Y298230
X789174Y290355
X793109Y298230
X797049Y290355
X800984Y298230
X804919Y290355
X808859Y298230
X812794Y290355
X816734Y298230
X820669Y290355
X832479Y298230
X836419Y290355
X840354Y298230
X844289Y290355
X848229Y298230
X852164Y290355
X856104Y298230
X860039Y290355
X863974Y298230
X867914Y290355
X871849Y298230
Y308070
X863974
X856104
X848229
X840354
X832479
X816734
X808859
X800984
X793109
X785234
X777364
X769489
X761614
X753739
X745864
X737994
X730119
X722244
X714369
X706494
X698624
X690749
X682874
X674999
X667124
X659254
X651379
X643504
X635629
X627754
X619884
X612009
X604134
X596259
X588384
X580514
X572639
X564764
X556889
X549014
X545079Y315945
X552954
X560829
X568699
X576574
X584449
X592324
X600199
X608069
X615944
X623819
X631694
X639569
X647439
X655314
X663189
X671064
X678939
X686809
X694684
X702559
X710434
X718309
X726179
X734054
X741929
X749804
X757679
X765549
X773424
X781299
X789174
X797049
X804919
X812794
X820669
X836419
X844289
X852164
X860039
X867914
T05
X402953Y23622
X413189
X423425
T06
X153937Y238898
Y246772
Y260551
X224015
Y246772
Y234961
T07
X1338526Y29526
Y21656
X1346396Y29526
Y21656
X1354271
Y29526
X1362146
Y21656
X1370021Y29526
Y21656
X1377896
Y29526
X1385766Y21656
Y29526
X141890Y269528
X131890
X121890
T08
X599941Y70118
X607933
X615925
X623917
X631909
X639901
X643937Y80118
X635945
X627953
X611889
X603897
X595905
T09
X1057086Y43267
X1066929
X1074803
X1084646
T10
X200000Y391500
Y401500
Y411500
Y421500
X216500
Y411500
Y401500
Y391500
X1296000Y329500
Y319500
X1367067Y96260
Y78544
Y60039
Y42323
X1392657
Y60039
Y78544
Y96260
T11
X1258504Y329331
X1272677Y349016
X1258504Y368701
T12
X180118Y729409
X190118
X200118
X210118
X220118
X230118
X240118
X250118
X260118
X270118
Y739409
X260118
X250118
X240118
X230118
X220118
X210118
X200118
X190118
X180118
T13
X590315Y19134
Y9134
X649527
Y19134
Y29134
T14
X585315Y44134
X654527
T15
X1045000Y32598
X1096732
T16
X19272Y337795
Y396850
X98838
Y337795
T17
X1379862Y108465
Y119095
T18
X1224016Y386221
T19
X1272441Y7087
X1299213
T20
X945197Y380000
X968819
T21
X1224016Y180709
T22
X35435Y373228
X82675
T23
X220472Y283071
X157480
X96890Y373228
X21220
T24
X90119Y72219
X15000Y1008622
X227041
X653974Y1008621
X955315Y850829
X1157095Y128841
X1387875Y-15015
X1385000Y1008622
T25
X537994Y303150
X825984
T26
X270078Y92125
Y155117
X490944Y79921
Y255118
X743897Y353543
Y410629
X1305117Y262745
X1376968Y216535
Y147243
X1305117Y87548
T27
X600925Y44134
X638917
T28
X355708Y96456
X450196Y257874
X572243Y337992
X332086Y408858
M30
